(kicad_pcb
	(version 20260206)
	(generator "pcbnew")
	(generator_version "10.0")
	(general
		(thickness 1.6)
		(legacy_teardrops no)
	)
	(paper "A4")
	(title_block
		(title "04192023_DAF0TMB3IC0_F0TG_MB_C_brd_V02_OCP.brd")
		(comment 1 "Grand Teton / footprints 4492-4497 of 8354")
	)
	(layers
		(0 "F.Cu" signal "TOP")
		(4 "In1.Cu" signal "GND")
		(6 "In2.Cu" signal "IN1")
		(8 "In3.Cu" signal "GND1")
		(10 "In4.Cu" signal "IN2")
		(12 "In5.Cu" signal "GND2")
		(14 "In6.Cu" signal "IN3")
		(16 "In7.Cu" signal "GND3")
		(18 "In8.Cu" signal "VCC")
		(20 "In9.Cu" signal "VCC1")
		(22 "In10.Cu" signal "GND4")
		(24 "In11.Cu" signal "IN4")
		(26 "In12.Cu" signal "GND5")
		(28 "In13.Cu" signal "IN5")
		(30 "In14.Cu" signal "GND6")
		(32 "In15.Cu" signal "IN6")
		(34 "In16.Cu" signal "GND7")
		(2 "B.Cu" signal "BOTTOM")
		(9 "F.Adhes" user "F.Adhesive")
		(11 "B.Adhes" user "B.Adhesive")
		(13 "F.Paste" user "Package Geometry/Pastemask Top")
		(15 "B.Paste" user "Package Geometry/Pastemask Bottom")
		(5 "F.SilkS" user "Ref Des/Silkscreen Top")
		(7 "B.SilkS" user "Ref Des/Silkscreen Bottom")
		(1 "F.Mask" user "Board Geometry/Soldermask Top")
		(3 "B.Mask" user "Board Geometry/Soldermask Bottom")
		(17 "Dwgs.User" user "User.Drawings")
		(19 "Cmts.User" user "User.Comments")
		(21 "Eco1.User" user "User.Eco1")
		(23 "Eco2.User" user "User.Eco2")
		(25 "Edge.Cuts" user "Board Geometry/Outline")
		(27 "Margin" user)
		(31 "F.CrtYd" user "Package Geometry/Place Bound Top")
		(29 "B.CrtYd" user "Package Geometry/Place Bound Bottom")
		(35 "F.Fab" user "Ref Des/Assembly Top")
		(33 "B.Fab" user "Ref Des/Assembly Bottom")
	)
	(footprint ""
		(layer "F.Cu")
		(at 441.470034 -69.861176 -90)
		(property "Reference" "Q56"
			(at -1.4478 3.592576 90)
			(unlocked yes)
			(layer "F.SilkS")
			(effects
				(font
					(size 0.7874 0.5842)
					(thickness 0.1524)
				)
			)
		)
		(property "Value" ""
			(at 0 0 270)
			(layer "F.Fab")
			(effects
				(font
					(size 1.27 1.27)
				)
			)
		)
		(duplicate_pad_numbers_are_jumpers no)
		(fp_line
			(start -2.350008 2.649982)
			(end -2.350008 2.413)
			(stroke
				(width 0.1524)
				(type default)
			)
			(layer "F.SilkS")
		)
		(fp_line
			(start 2.350008 2.649982)
			(end -2.350008 2.649982)
			(stroke
				(width 0.1524)
				(type default)
			)
			(layer "F.SilkS")
		)
		(fp_line
			(start 2.350008 2.4892)
			(end 2.350008 2.649982)
			(stroke
				(width 0.1524)
				(type default)
			)
			(layer "F.SilkS")
		)
		(fp_line
			(start -2.350008 -2.4384)
			(end -2.350008 -2.649982)
			(stroke
				(width 0.1524)
				(type default)
			)
			(layer "F.SilkS")
		)
		(fp_line
			(start -2.350008 -2.649982)
			(end 2.350008 -2.649982)
			(stroke
				(width 0.1524)
				(type default)
			)
			(layer "F.SilkS")
		)
		(fp_line
			(start 2.350008 -2.649982)
			(end 2.350008 -2.4892)
			(stroke
				(width 0.1524)
				(type default)
			)
			(layer "F.SilkS")
		)
		(fp_poly
			(pts
				(xy -2.58699 -3.70967) (xy -3.00609 -2.66827) (xy -3.38709 -3.70967)
			)
			(stroke
				(width 0)
				(type default)
			)
			(fill yes)
			(layer "F.SilkS")
		)
		(fp_line
			(start -2.350008 2.649982)
			(end -2.350008 -2.649982)
			(stroke
				(width 0.1)
				(type default)
			)
			(layer "F.Fab")
		)
		(fp_line
			(start 2.350008 2.649982)
			(end -2.350008 2.649982)
			(stroke
				(width 0.1)
				(type default)
			)
			(layer "F.Fab")
		)
		(fp_line
			(start -2.350008 -2.649982)
			(end 2.350008 -2.649982)
			(stroke
				(width 0.1)
				(type default)
			)
			(layer "F.Fab")
		)
		(fp_line
			(start 2.350008 -2.649982)
			(end 2.350008 2.649982)
			(stroke
				(width 0.1)
				(type default)
			)
			(layer "F.Fab")
		)
		(fp_poly
			(pts
				(xy -3.717544 -1.905) (xy -4.758944 -2.3241) (xy -4.758944 -1.524)
			)
			(stroke
				(width 0)
				(type default)
			)
			(fill yes)
			(layer "F.Fab")
		)
		(pad "1" smd rect
			(at -2.999994 -1.905 180)
			(size 0.7112 1.1684)
			(layers "F.Cu" "F.Mask" "F.Paste")
			(net "P3V3")
		)
		(pad "2" smd rect
			(at -2.999994 -0.635 180)
			(size 0.7112 1.1684)
			(layers "F.Cu" "F.Mask" "F.Paste")
			(net "P3V3")
		)
		(pad "3" smd rect
			(at -2.999994 0.635 180)
			(size 0.7112 1.1684)
			(layers "F.Cu" "F.Mask" "F.Paste")
			(net "P3V3")
		)
		(pad "4" smd rect
			(at -2.999994 1.905 180)
			(size 0.7112 1.1684)
			(layers "F.Cu" "F.Mask" "F.Paste")
			(net "SW_P3V3_EN_ISO_R")
		)
		(pad "5" smd circle
			(at 0.925068 0 180)
			(size 0 0)
			(layers "F.Cu" "F.Mask" "F.Paste")
			(net "P3V3_AUX")
		)
		(zone
			(layer "F.Cu")
			(hatch none 0.5)
			(connect_pads
				(clearance 0)
			)
			(min_thickness 0.25)
			(keepout
				(tracks not_allowed)
				(vias allowed)
				(pads allowed)
				(copperpour not_allowed)
				(footprints allowed)
			)
			(placement
				(enabled no)
				(sheetname "")
			)
			(fill
				(thermal_gap 0.5)
				(thermal_bridge_width 0.5)
				(island_removal_mode 0)
			)
			(polygon
				(pts
					(xy 443.629034 -71.308976) (xy 439.311034 -71.308976) (xy 438.828434 -71.308976) (xy 438.828434 -72.210676)
					(xy 444.111634 -72.210676) (xy 444.111634 -71.571104) (xy 443.849506 -71.308976)
				)
			)
		)
	)
	(footprint ""
		(layer "F.Cu")
		(at 156.30779 -103.738934 90)
		(property "Reference" "C1873"
			(at 0 0 90)
			(layer "F.SilkS")
			(hide yes)
			(effects
				(font
					(size 1.27 1.27)
				)
			)
		)
		(property "Value" ""
			(at 0 0 90)
			(layer "F.Fab")
			(effects
				(font
					(size 1.27 1.27)
				)
			)
		)
		(duplicate_pad_numbers_are_jumpers no)
		(fp_line
			(start 0.7874 -0.4064)
			(end 0.7874 0.4064)
			(stroke
				(width 0.1524)
				(type default)
			)
			(layer "F.SilkS")
		)
		(fp_line
			(start -0.7874 -0.4064)
			(end 0.7874 -0.4064)
			(stroke
				(width 0.1524)
				(type default)
			)
			(layer "F.SilkS")
		)
		(fp_line
			(start 0.7874 0.4064)
			(end -0.7874 0.4064)
			(stroke
				(width 0.1524)
				(type default)
			)
			(layer "F.SilkS")
		)
		(fp_line
			(start -0.7874 0.4064)
			(end -0.7874 -0.4064)
			(stroke
				(width 0.1524)
				(type default)
			)
			(layer "F.SilkS")
		)
		(fp_line
			(start -0.12065 -0.305054)
			(end -0.12065 -0.2794)
			(stroke
				(width 0.1)
				(type default)
			)
			(layer "F.Fab")
		)
		(fp_line
			(start -0.67945 -0.305054)
			(end -0.12065 -0.305054)
			(stroke
				(width 0.1)
				(type default)
			)
			(layer "F.Fab")
		)
		(fp_line
			(start 0.67945 -0.3048)
			(end 0.67945 0.3048)
			(stroke
				(width 0.1)
				(type default)
			)
			(layer "F.Fab")
		)
		(fp_line
			(start 0.12065 -0.3048)
			(end 0.67945 -0.3048)
			(stroke
				(width 0.1)
				(type default)
			)
			(layer "F.Fab")
		)
		(fp_line
			(start 0.12065 -0.2794)
			(end 0.12065 -0.3048)
			(stroke
				(width 0.1)
				(type default)
			)
			(layer "F.Fab")
		)
		(fp_line
			(start -0.12065 -0.2794)
			(end 0.12065 -0.2794)
			(stroke
				(width 0.1)
				(type default)
			)
			(layer "F.Fab")
		)
		(fp_line
			(start 0.120396 0.2794)
			(end -0.12065 0.2794)
			(stroke
				(width 0.1)
				(type default)
			)
			(layer "F.Fab")
		)
		(fp_line
			(start -0.12065 0.2794)
			(end -0.12065 0.3048)
			(stroke
				(width 0.1)
				(type default)
			)
			(layer "F.Fab")
		)
		(fp_line
			(start 0.67945 0.3048)
			(end 0.120396 0.3048)
			(stroke
				(width 0.1)
				(type default)
			)
			(layer "F.Fab")
		)
		(fp_line
			(start 0.120396 0.3048)
			(end 0.120396 0.2794)
			(stroke
				(width 0.1)
				(type default)
			)
			(layer "F.Fab")
		)
		(fp_line
			(start -0.12065 0.3048)
			(end -0.67945 0.3048)
			(stroke
				(width 0.1)
				(type default)
			)
			(layer "F.Fab")
		)
		(fp_line
			(start -0.67945 0.3048)
			(end -0.67945 -0.305054)
			(stroke
				(width 0.1)
				(type default)
			)
			(layer "F.Fab")
		)
		(pad "1" smd circle
			(at -0.40005 0 90)
			(size 0 0)
			(layers "F.Cu" "F.Mask" "F.Paste")
			(net "P3V3_AUX")
		)
		(pad "2" smd circle
			(at 0.40005 0 90)
			(size 0 0)
			(layers "F.Cu" "F.Mask" "F.Paste")
			(net "GND")
		)
	)
	(footprint ""
		(layer "F.Cu")
		(at 80.913478 -23.317962)
		(property "Reference" "PC2150"
			(at 0 0 0)
			(layer "F.SilkS")
			(hide yes)
			(effects
				(font
					(size 1.27 1.27)
				)
			)
		)
		(property "Value" ""
			(at 0 0 0)
			(layer "F.Fab")
			(effects
				(font
					(size 1.27 1.27)
				)
			)
		)
		(duplicate_pad_numbers_are_jumpers no)
		(fp_line
			(start -0.7874 -0.4064)
			(end 0.7874 -0.4064)
			(stroke
				(width 0.1524)
				(type default)
			)
			(layer "F.SilkS")
		)
		(fp_line
			(start -0.7874 0.4064)
			(end -0.7874 -0.4064)
			(stroke
				(width 0.1524)
				(type default)
			)
			(layer "F.SilkS")
		)
		(fp_line
			(start 0.7874 -0.4064)
			(end 0.7874 0.4064)
			(stroke
				(width 0.1524)
				(type default)
			)
			(layer "F.SilkS")
		)
		(fp_line
			(start 0.7874 0.4064)
			(end -0.7874 0.4064)
			(stroke
				(width 0.1524)
				(type default)
			)
			(layer "F.SilkS")
		)
		(fp_line
			(start -0.67945 -0.305054)
			(end -0.12065 -0.305054)
			(stroke
				(width 0.1)
				(type default)
			)
			(layer "F.Fab")
		)
		(fp_line
			(start -0.67945 0.3048)
			(end -0.67945 -0.305054)
			(stroke
				(width 0.1)
				(type default)
			)
			(layer "F.Fab")
		)
		(fp_line
			(start -0.12065 -0.305054)
			(end -0.12065 -0.2794)
			(stroke
				(width 0.1)
				(type default)
			)
			(layer "F.Fab")
		)
		(fp_line
			(start -0.12065 -0.2794)
			(end 0.12065 -0.2794)
			(stroke
				(width 0.1)
				(type default)
			)
			(layer "F.Fab")
		)
		(fp_line
			(start -0.12065 0.2794)
			(end -0.12065 0.3048)
			(stroke
				(width 0.1)
				(type default)
			)
			(layer "F.Fab")
		)
		(fp_line
			(start -0.12065 0.3048)
			(end -0.67945 0.3048)
			(stroke
				(width 0.1)
				(type default)
			)
			(layer "F.Fab")
		)
		(fp_line
			(start 0.120396 0.2794)
			(end -0.12065 0.2794)
			(stroke
				(width 0.1)
				(type default)
			)
			(layer "F.Fab")
		)
		(fp_line
			(start 0.120396 0.3048)
			(end 0.120396 0.2794)
			(stroke
				(width 0.1)
				(type default)
			)
			(layer "F.Fab")
		)
		(fp_line
			(start 0.12065 -0.3048)
			(end 0.67945 -0.3048)
			(stroke
				(width 0.1)
				(type default)
			)
			(layer "F.Fab")
		)
		(fp_line
			(start 0.12065 -0.2794)
			(end 0.12065 -0.3048)
			(stroke
				(width 0.1)
				(type default)
			)
			(layer "F.Fab")
		)
		(fp_line
			(start 0.67945 -0.3048)
			(end 0.67945 0.3048)
			(stroke
				(width 0.1)
				(type default)
			)
			(layer "F.Fab")
		)
		(fp_line
			(start 0.67945 0.3048)
			(end 0.120396 0.3048)
			(stroke
				(width 0.1)
				(type default)
			)
			(layer "F.Fab")
		)
		(pad "1" smd circle
			(at -0.40005 0)
			(size 0 0)
			(layers "F.Cu" "F.Mask" "F.Paste")
			(net "P12V_OCP_GATE_2")
		)
		(pad "2" smd circle
			(at 0.40005 0)
			(size 0 0)
			(layers "F.Cu" "F.Mask" "F.Paste")
			(net "GND")
		)
	)
	(footprint ""
		(layer "F.Cu")
		(at 100.884736 -127.787654 -90)
		(property "Reference" "R1457"
			(at 0 0 270)
			(layer "F.SilkS")
			(hide yes)
			(effects
				(font
					(size 1.27 1.27)
				)
			)
		)
		(property "Value" ""
			(at 0 0 270)
			(layer "F.Fab")
			(effects
				(font
					(size 1.27 1.27)
				)
			)
		)
		(duplicate_pad_numbers_are_jumpers no)
		(fp_line
			(start -0.7874 0.4064)
			(end -0.7874 -0.4064)
			(stroke
				(width 0.1524)
				(type default)
			)
			(layer "F.SilkS")
		)
		(fp_line
			(start 0.7874 0.4064)
			(end -0.7874 0.4064)
			(stroke
				(width 0.1524)
				(type default)
			)
			(layer "F.SilkS")
		)
		(fp_line
			(start -0.7874 -0.4064)
			(end 0.7874 -0.4064)
			(stroke
				(width 0.1524)
				(type default)
			)
			(layer "F.SilkS")
		)
		(fp_line
			(start 0.7874 -0.4064)
			(end 0.7874 0.4064)
			(stroke
				(width 0.1524)
				(type default)
			)
			(layer "F.SilkS")
		)
		(fp_line
			(start -0.67945 0.3048)
			(end -0.67945 -0.305054)
			(stroke
				(width 0.1)
				(type default)
			)
			(layer "F.Fab")
		)
		(fp_line
			(start -0.12065 0.3048)
			(end -0.67945 0.3048)
			(stroke
				(width 0.1)
				(type default)
			)
			(layer "F.Fab")
		)
		(fp_line
			(start 0.120396 0.3048)
			(end 0.120396 0.2794)
			(stroke
				(width 0.1)
				(type default)
			)
			(layer "F.Fab")
		)
		(fp_line
			(start 0.67945 0.3048)
			(end 0.120396 0.3048)
			(stroke
				(width 0.1)
				(type default)
			)
			(layer "F.Fab")
		)
		(fp_line
			(start -0.12065 0.2794)
			(end -0.12065 0.3048)
			(stroke
				(width 0.1)
				(type default)
			)
			(layer "F.Fab")
		)
		(fp_line
			(start 0.120396 0.2794)
			(end -0.12065 0.2794)
			(stroke
				(width 0.1)
				(type default)
			)
			(layer "F.Fab")
		)
		(fp_line
			(start -0.12065 -0.2794)
			(end 0.12065 -0.2794)
			(stroke
				(width 0.1)
				(type default)
			)
			(layer "F.Fab")
		)
		(fp_line
			(start 0.12065 -0.2794)
			(end 0.12065 -0.3048)
			(stroke
				(width 0.1)
				(type default)
			)
			(layer "F.Fab")
		)
		(fp_line
			(start 0.12065 -0.3048)
			(end 0.67945 -0.3048)
			(stroke
				(width 0.1)
				(type default)
			)
			(layer "F.Fab")
		)
		(fp_line
			(start 0.67945 -0.3048)
			(end 0.67945 0.3048)
			(stroke
				(width 0.1)
				(type default)
			)
			(layer "F.Fab")
		)
		(fp_line
			(start -0.67945 -0.305054)
			(end -0.12065 -0.305054)
			(stroke
				(width 0.1)
				(type default)
			)
			(layer "F.Fab")
		)
		(fp_line
			(start -0.12065 -0.305054)
			(end -0.12065 -0.2794)
			(stroke
				(width 0.1)
				(type default)
			)
			(layer "F.Fab")
		)
		(pad "1" smd circle
			(at -0.40005 0 270)
			(size 0 0)
			(layers "F.Cu" "F.Mask" "F.Paste")
			(net "P1V8_AUX")
		)
		(pad "2" smd circle
			(at 0.40005 0 270)
			(size 0 0)
			(layers "F.Cu" "F.Mask" "F.Paste")
			(net "PWRGD_P12V_MEM_CPU0")
		)
	)
	(footprint ""
		(layer "F.Cu")
		(at 461.916526 -100.470208)
		(property "Reference" "C639"
			(at 0 0 0)
			(layer "F.SilkS")
			(hide yes)
			(effects
				(font
					(size 1.27 1.27)
				)
			)
		)
		(property "Value" ""
			(at 0 0 0)
			(layer "F.Fab")
			(effects
				(font
					(size 1.27 1.27)
				)
			)
		)
		(duplicate_pad_numbers_are_jumpers no)
		(fp_line
			(start -0.7874 -0.4064)
			(end 0.7874 -0.4064)
			(stroke
				(width 0.1524)
				(type default)
			)
			(layer "F.SilkS")
		)
		(fp_line
			(start -0.7874 0.4064)
			(end -0.7874 -0.4064)
			(stroke
				(width 0.1524)
				(type default)
			)
			(layer "F.SilkS")
		)
		(fp_line
			(start 0.7874 -0.4064)
			(end 0.7874 0.4064)
			(stroke
				(width 0.1524)
				(type default)
			)
			(layer "F.SilkS")
		)
		(fp_line
			(start 0.7874 0.4064)
			(end -0.7874 0.4064)
			(stroke
				(width 0.1524)
				(type default)
			)
			(layer "F.SilkS")
		)
		(fp_line
			(start -0.67945 -0.305054)
			(end -0.12065 -0.305054)
			(stroke
				(width 0.1)
				(type default)
			)
			(layer "F.Fab")
		)
		(fp_line
			(start -0.67945 0.3048)
			(end -0.67945 -0.305054)
			(stroke
				(width 0.1)
				(type default)
			)
			(layer "F.Fab")
		)
		(fp_line
			(start -0.12065 -0.305054)
			(end -0.12065 -0.2794)
			(stroke
				(width 0.1)
				(type default)
			)
			(layer "F.Fab")
		)
		(fp_line
			(start -0.12065 -0.2794)
			(end 0.12065 -0.2794)
			(stroke
				(width 0.1)
				(type default)
			)
			(layer "F.Fab")
		)
		(fp_line
			(start -0.12065 0.2794)
			(end -0.12065 0.3048)
			(stroke
				(width 0.1)
				(type default)
			)
			(layer "F.Fab")
		)
		(fp_line
			(start -0.12065 0.3048)
			(end -0.67945 0.3048)
			(stroke
				(width 0.1)
				(type default)
			)
			(layer "F.Fab")
		)
		(fp_line
			(start 0.120396 0.2794)
			(end -0.12065 0.2794)
			(stroke
				(width 0.1)
				(type default)
			)
			(layer "F.Fab")
		)
		(fp_line
			(start 0.120396 0.3048)
			(end 0.120396 0.2794)
			(stroke
				(width 0.1)
				(type default)
			)
			(layer "F.Fab")
		)
		(fp_line
			(start 0.12065 -0.3048)
			(end 0.67945 -0.3048)
			(stroke
				(width 0.1)
				(type default)
			)
			(layer "F.Fab")
		)
		(fp_line
			(start 0.12065 -0.2794)
			(end 0.12065 -0.3048)
			(stroke
				(width 0.1)
				(type default)
			)
			(layer "F.Fab")
		)
		(fp_line
			(start 0.67945 -0.3048)
			(end 0.67945 0.3048)
			(stroke
				(width 0.1)
				(type default)
			)
			(layer "F.Fab")
		)
		(fp_line
			(start 0.67945 0.3048)
			(end 0.120396 0.3048)
			(stroke
				(width 0.1)
				(type default)
			)
			(layer "F.Fab")
		)
		(pad "1" smd circle
			(at -0.40005 0)
			(size 0 0)
			(layers "F.Cu" "F.Mask" "F.Paste")
			(net "P3V3_AUX")
		)
		(pad "2" smd circle
			(at 0.40005 0)
			(size 0 0)
			(layers "F.Cu" "F.Mask" "F.Paste")
			(net "GND")
		)
	)
	(footprint ""
		(layer "F.Cu")
		(at 256.210308 -110.090204)
		(property "Reference" "C1823"
			(at 0 0 0)
			(layer "F.SilkS")
			(hide yes)
			(effects
				(font
					(size 1.27 1.27)
				)
			)
		)
		(property "Value" ""
			(at 0 0 0)
			(layer "F.Fab")
			(effects
				(font
					(size 1.27 1.27)
				)
			)
		)
		(duplicate_pad_numbers_are_jumpers no)
		(fp_line
			(start -0.7874 -0.4064)
			(end 0.7874 -0.4064)
			(stroke
				(width 0.1524)
				(type default)
			)
			(layer "F.SilkS")
		)
		(fp_line
			(start -0.7874 0.4064)
			(end -0.7874 -0.4064)
			(stroke
				(width 0.1524)
				(type default)
			)
			(layer "F.SilkS")
		)
		(fp_line
			(start 0.7874 -0.4064)
			(end 0.7874 0.4064)
			(stroke
				(width 0.1524)
				(type default)
			)
			(layer "F.SilkS")
		)
		(fp_line
			(start 0.7874 0.4064)
			(end -0.7874 0.4064)
			(stroke
				(width 0.1524)
				(type default)
			)
			(layer "F.SilkS")
		)
		(fp_line
			(start -0.67945 -0.305054)
			(end -0.12065 -0.305054)
			(stroke
				(width 0.1)
				(type default)
			)
			(layer "F.Fab")
		)
		(fp_line
			(start -0.67945 0.3048)
			(end -0.67945 -0.305054)
			(stroke
				(width 0.1)
				(type default)
			)
			(layer "F.Fab")
		)
		(fp_line
			(start -0.12065 -0.305054)
			(end -0.12065 -0.2794)
			(stroke
				(width 0.1)
				(type default)
			)
			(layer "F.Fab")
		)
		(fp_line
			(start -0.12065 -0.2794)
			(end 0.12065 -0.2794)
			(stroke
				(width 0.1)
				(type default)
			)
			(layer "F.Fab")
		)
		(fp_line
			(start -0.12065 0.2794)
			(end -0.12065 0.3048)
			(stroke
				(width 0.1)
				(type default)
			)
			(layer "F.Fab")
		)
		(fp_line
			(start -0.12065 0.3048)
			(end -0.67945 0.3048)
			(stroke
				(width 0.1)
				(type default)
			)
			(layer "F.Fab")
		)
		(fp_line
			(start 0.120396 0.2794)
			(end -0.12065 0.2794)
			(stroke
				(width 0.1)
				(type default)
			)
			(layer "F.Fab")
		)
		(fp_line
			(start 0.120396 0.3048)
			(end 0.120396 0.2794)
			(stroke
				(width 0.1)
				(type default)
			)
			(layer "F.Fab")
		)
		(fp_line
			(start 0.12065 -0.3048)
			(end 0.67945 -0.3048)
			(stroke
				(width 0.1)
				(type default)
			)
			(layer "F.Fab")
		)
		(fp_line
			(start 0.12065 -0.2794)
			(end 0.12065 -0.3048)
			(stroke
				(width 0.1)
				(type default)
			)
			(layer "F.Fab")
		)
		(fp_line
			(start 0.67945 -0.3048)
			(end 0.67945 0.3048)
			(stroke
				(width 0.1)
				(type default)
			)
			(layer "F.Fab")
		)
		(fp_line
			(start 0.67945 0.3048)
			(end 0.120396 0.3048)
			(stroke
				(width 0.1)
				(type default)
			)
			(layer "F.Fab")
		)
		(pad "1" smd circle
			(at -0.40005 0)
			(size 0 0)
			(layers "F.Cu" "F.Mask" "F.Paste")
			(net "P3V3_AUX")
		)
		(pad "2" smd circle
			(at 0.40005 0)
			(size 0 0)
			(layers "F.Cu" "F.Mask" "F.Paste")
			(net "GND")
		)
	)
)
